(kicad_pcb
	(version 20241229)
	(generator "pcbnew")
	(generator_version "9.0")
	(general
		(thickness 1.6296)
		(legacy_teardrops no)
	)
	(paper "A3")
	(title_block
		(title "Thunderbolt to 10GbE adapter")
		(date "2026-04-21")
		(rev "1.1.0")
		(company "Antmicro Ltd")
		(comment 1 "www.antmicro.com")
		(comment 9 "footprints 520-525 of 703")
	)
	(layers
		(0 "F.Cu" signal)
		(4 "In1.Cu" signal)
		(6 "In2.Cu" signal)
		(8 "In3.Cu" signal)
		(10 "In4.Cu" signal)
		(12 "In5.Cu" signal)
		(14 "In6.Cu" signal)
		(2 "B.Cu" signal)
		(9 "F.Adhes" user "F.Adhesive")
		(11 "B.Adhes" user "B.Adhesive")
		(13 "F.Paste" user)
		(15 "B.Paste" user)
		(5 "F.SilkS" user "F.Silkscreen")
		(7 "B.SilkS" user "B.Silkscreen")
		(1 "F.Mask" user)
		(3 "B.Mask" user)
		(17 "Dwgs.User" user "User.Drawings")
		(19 "Cmts.User" user "User.Comments")
		(21 "Eco1.User" user "User.Eco1")
		(23 "Eco2.User" user "User.Eco2")
		(25 "Edge.Cuts" user)
		(27 "Margin" user)
		(31 "F.CrtYd" user "F.Courtyard")
		(29 "B.CrtYd" user "B.Courtyard")
		(35 "F.Fab" user)
		(33 "B.Fab" user)
	)
	(footprint "antmicro-footprints:TP_SMD_0.75mm"
		(layer "B.Cu")
		(at 138.25 57.75 90)
		(property "Reference" "TP38"
			(at 3.15 0.45 270)
			(layer "B.SilkS")
			(effects
				(font
					(size 0.7 0.7)
					(thickness 0.15)
				)
				(justify left bottom mirror)
			)
		)
		(property "Value" "TP_0.75mm_SMD"
			(at 0 -1.2 270)
			(layer "B.Fab")
			(effects
				(font
					(size 0.7 0.7)
					(thickness 0.15)
				)
				(justify left bottom mirror)
			)
		)
		(property "Description" "SMT test point"
			(at 0 0 270)
			(layer "B.Fab")
			(hide yes)
			(effects
				(font
					(size 1.27 1.27)
					(thickness 0.15)
				)
				(justify mirror)
			)
		)
		(property "MPN" ""
			(at 0 0 90)
			(unlocked yes)
			(layer "B.Fab")
			(hide yes)
			(effects
				(font
					(size 1 1)
					(thickness 0.15)
				)
				(justify mirror)
			)
		)
		(property "Manufacturer" ""
			(at 0 0 90)
			(unlocked yes)
			(layer "B.Fab")
			(hide yes)
			(effects
				(font
					(size 1 1)
					(thickness 0.15)
				)
				(justify mirror)
			)
		)
		(property "Author" "Antmicro"
			(at 0 0 90)
			(unlocked yes)
			(layer "B.Fab")
			(hide yes)
			(effects
				(font
					(size 1 1)
					(thickness 0.15)
				)
				(justify mirror)
			)
		)
		(property "License" "Apache-2.0"
			(at 0 0 90)
			(unlocked yes)
			(layer "B.Fab")
			(hide yes)
			(effects
				(font
					(size 1 1)
					(thickness 0.15)
				)
				(justify mirror)
			)
		)
		(sheetname "/Power input/")
		(sheetfile "power_input.kicad_sch")
		(attr exclude_from_pos_files exclude_from_bom)
		(fp_circle
			(center 0 0)
			(end 0.475 0)
			(stroke
				(width 0.05)
				(type default)
			)
			(fill no)
			(layer "B.CrtYd")
		)
		(fp_text user "${REFERENCE}"
			(at -0.4 -2.7 270)
			(layer "B.Fab")
			(effects
				(font
					(size 0.7 0.7)
					(thickness 0.15)
				)
				(justify left bottom mirror)
			)
		)
		(fp_text user "License: Apache-2.0"
			(at -0.4 -5.101 270)
			(layer "B.Fab")
			(effects
				(font
					(size 0.7 0.7)
					(thickness 0.15)
				)
				(justify left bottom mirror)
			)
		)
		(fp_text user "Author: Antmicro"
			(at -0.4 -3.901 270)
			(layer "B.Fab")
			(effects
				(font
					(size 0.7 0.7)
					(thickness 0.15)
				)
				(justify left bottom mirror)
			)
		)
		(pad "1" smd circle
			(at 0 0 90)
			(size 0.75 0.75)
			(layers "B.Cu" "B.Mask")
			(net 53 "+5V_USB")
			(pinfunction "1")
			(pintype "passive")
		)
	)
	(footprint "antmicro-footprints:C_0603_1608Metric_EIA"
		(layer "B.Cu")
		(at 163.25 130.5 180)
		(descr "Capacitor SMD 0603, IPC-7351 Density Level A")
		(tags "Capacitor 0603")
		(property "Reference" "C289"
			(at -4.5 2 0)
			(layer "B.SilkS")
			(effects
				(font
					(size 0.7 0.7)
					(thickness 0.15)
				)
				(justify left bottom mirror)
			)
		)
		(property "Value" "C_22u_16V_0603"
			(at -1.42757 -1.770288 0)
			(layer "B.Fab")
			(effects
				(font
					(size 0.7 0.7)
					(thickness 0.15)
				)
				(justify left bottom mirror)
			)
		)
		(property "Datasheet" "https://product.samsungsem.com/mlcc/CL10A226MO7JZN.do"
			(at 0 0 0)
			(layer "B.Fab")
			(hide yes)
			(effects
				(font
					(size 1.27 1.27)
					(thickness 0.15)
				)
				(justify mirror)
			)
		)
		(property "Description" "SMD Multilayer Ceramic Capacitor"
			(at 0 0 0)
			(layer "B.Fab")
			(hide yes)
			(effects
				(font
					(size 1.27 1.27)
					(thickness 0.15)
				)
				(justify mirror)
			)
		)
		(property "MPN" "CL10A226MO7JZNC"
			(at 0 0 180)
			(unlocked yes)
			(layer "B.Fab")
			(hide yes)
			(effects
				(font
					(size 1 1)
					(thickness 0.15)
				)
				(justify mirror)
			)
		)
		(property "Manufacturer" "Samsung Electro-Mechanics"
			(at 0 0 180)
			(unlocked yes)
			(layer "B.Fab")
			(hide yes)
			(effects
				(font
					(size 1 1)
					(thickness 0.15)
				)
				(justify mirror)
			)
		)
		(property "License" "Apache-2.0"
			(at 0 0 180)
			(unlocked yes)
			(layer "B.Fab")
			(hide yes)
			(effects
				(font
					(size 1 1)
					(thickness 0.15)
				)
				(justify mirror)
			)
		)
		(property "Author" "Antmicro"
			(at 0 0 180)
			(unlocked yes)
			(layer "B.Fab")
			(hide yes)
			(effects
				(font
					(size 1 1)
					(thickness 0.15)
				)
				(justify mirror)
			)
		)
		(property "Val" "22u"
			(at 0 0 180)
			(unlocked yes)
			(layer "B.Fab")
			(hide yes)
			(effects
				(font
					(size 1 1)
					(thickness 0.15)
				)
				(justify mirror)
			)
		)
		(property "Voltage" "16V"
			(at 0 0 180)
			(unlocked yes)
			(layer "B.Fab")
			(hide yes)
			(effects
				(font
					(size 1 1)
					(thickness 0.15)
				)
				(justify mirror)
			)
		)
		(property "Dielectric" ""
			(at 0 0 180)
			(unlocked yes)
			(layer "B.Fab")
			(hide yes)
			(effects
				(font
					(size 1 1)
					(thickness 0.15)
				)
				(justify mirror)
			)
		)
		(sheetname "/2xRJ45/")
		(sheetfile "2xrj45.kicad_sch")
		(attr smd)
		(fp_line
			(start -0.15 0.55)
			(end 0.15 0.55)
			(stroke
				(width 0.15)
				(type solid)
			)
			(layer "B.SilkS")
		)
		(fp_line
			(start -0.15 -0.55)
			(end 0.15 -0.55)
			(stroke
				(width 0.15)
				(type solid)
			)
			(layer "B.SilkS")
		)
		(fp_rect
			(start -1.25 0.65)
			(end 1.25 -0.65)
			(stroke
				(width 0.05)
				(type solid)
			)
			(fill no)
			(layer "B.CrtYd")
		)
		(fp_rect
			(start -0.8 0.45)
			(end 0.8 -0.45)
			(stroke
				(width 0.15)
				(type solid)
			)
			(fill no)
			(layer "B.Fab")
		)
		(fp_text user "${REFERENCE}"
			(at -1.682 -3.895 0)
			(layer "B.Fab")
			(effects
				(font
					(size 0.7 0.7)
					(thickness 0.15)
				)
				(justify left bottom mirror)
			)
		)
		(fp_text user "Author: Antmicro"
			(at -1.682 -4.894 0)
			(layer "B.Fab")
			(effects
				(font
					(size 0.7 0.7)
					(thickness 0.15)
				)
				(justify left bottom mirror)
			)
		)
		(fp_text user "License: Apache-2.0"
			(at -1.682 -5.895 0)
			(layer "B.Fab")
			(effects
				(font
					(size 0.7 0.7)
					(thickness 0.15)
				)
				(justify left bottom mirror)
			)
		)
		(pad "1" smd roundrect
			(at -0.7 0 180)
			(size 0.8 1.1)
			(layers "B.Cu" "B.Mask" "B.Paste")
			(roundrect_rratio 0.2)
			(net 23 "GND")
			(pintype "passive")
		)
		(pad "2" smd roundrect
			(at 0.7 0 180)
			(size 0.8 1.1)
			(layers "B.Cu" "B.Mask" "B.Paste")
			(roundrect_rratio 0.2)
			(net 18 "+1V88")
			(pintype "passive")
		)
	)
	(footprint "antmicro-footprints:TP_SMD_0.75mm"
		(layer "B.Cu")
		(at 158.231866 62.935117 180)
		(property "Reference" "TP26"
			(at -0.368134 3.135117 90)
			(layer "B.SilkS")
			(effects
				(font
					(size 0.7 0.7)
					(thickness 0.15)
				)
				(justify left bottom mirror)
			)
		)
		(property "Value" "TP_0.75mm_SMD"
			(at 0 -1.2 0)
			(layer "B.Fab")
			(effects
				(font
					(size 0.7 0.7)
					(thickness 0.15)
				)
				(justify left bottom mirror)
			)
		)
		(property "Description" "SMT test point"
			(at 0 0 0)
			(layer "B.Fab")
			(hide yes)
			(effects
				(font
					(size 1.27 1.27)
					(thickness 0.15)
				)
				(justify mirror)
			)
		)
		(property "MPN" ""
			(at 0 0 180)
			(unlocked yes)
			(layer "B.Fab")
			(hide yes)
			(effects
				(font
					(size 1 1)
					(thickness 0.15)
				)
				(justify mirror)
			)
		)
		(property "Manufacturer" ""
			(at 0 0 180)
			(unlocked yes)
			(layer "B.Fab")
			(hide yes)
			(effects
				(font
					(size 1 1)
					(thickness 0.15)
				)
				(justify mirror)
			)
		)
		(property "Author" "Antmicro"
			(at 0 0 180)
			(unlocked yes)
			(layer "B.Fab")
			(hide yes)
			(effects
				(font
					(size 1 1)
					(thickness 0.15)
				)
				(justify mirror)
			)
		)
		(property "License" "Apache-2.0"
			(at 0 0 180)
			(unlocked yes)
			(layer "B.Fab")
			(hide yes)
			(effects
				(font
					(size 1 1)
					(thickness 0.15)
				)
				(justify mirror)
			)
		)
		(sheetname "/X710-AT2 Misc/")
		(sheetfile "x710-at2-mics.kicad_sch")
		(attr exclude_from_pos_files exclude_from_bom)
		(fp_circle
			(center 0 0)
			(end 0.475 0)
			(stroke
				(width 0.05)
				(type default)
			)
			(fill no)
			(layer "B.CrtYd")
		)
		(fp_text user "${REFERENCE}"
			(at -0.4 -2.7 0)
			(layer "B.Fab")
			(effects
				(font
					(size 0.7 0.7)
					(thickness 0.15)
				)
				(justify left bottom mirror)
			)
		)
		(fp_text user "License: Apache-2.0"
			(at -0.4 -5.101 0)
			(layer "B.Fab")
			(effects
				(font
					(size 0.7 0.7)
					(thickness 0.15)
				)
				(justify left bottom mirror)
			)
		)
		(fp_text user "Author: Antmicro"
			(at -0.4 -3.901 0)
			(layer "B.Fab")
			(effects
				(font
					(size 0.7 0.7)
					(thickness 0.15)
				)
				(justify left bottom mirror)
			)
		)
		(pad "1" smd circle
			(at 0 0 180)
			(size 0.75 0.75)
			(layers "B.Cu" "B.Mask")
			(net 140 "/X710-AT2 Misc/NCSI.TXD_0")
			(pinfunction "1")
			(pintype "passive")
		)
	)
	(footprint "antmicro-footprints:Fiducial_1mm_Mask2mm"
		(layer "B.Cu")
		(at 179 129 180)
		(descr "Circular Fiducial, 1mm bare copper, 3mm soldermask opening")
		(tags "fiducial")
		(property "Reference" "FD6"
			(at -3.5 -0.5 0)
			(layer "B.SilkS")
			(effects
				(font
					(size 0.7 0.7)
					(thickness 0.15)
				)
				(justify left bottom mirror)
			)
		)
		(property "Value" "Fiducial_1mm_Mask2mm"
			(at 0 -2.2 0)
			(layer "B.Fab")
			(effects
				(font
					(size 0.7 0.7)
					(thickness 0.15)
				)
				(justify left bottom mirror)
			)
		)
		(property "Description" "Fiducial mask"
			(at 0 0 0)
			(layer "B.Fab")
			(hide yes)
			(effects
				(font
					(size 1.27 1.27)
					(thickness 0.15)
				)
				(justify mirror)
			)
		)
		(property "Author" "Antmicro"
			(at 0 0 180)
			(unlocked yes)
			(layer "B.Fab")
			(hide yes)
			(effects
				(font
					(size 1 1)
					(thickness 0.15)
				)
				(justify mirror)
			)
		)
		(property "License" "Apache-2.0"
			(at 0 0 180)
			(unlocked yes)
			(layer "B.Fab")
			(hide yes)
			(effects
				(font
					(size 1 1)
					(thickness 0.15)
				)
				(justify mirror)
			)
		)
		(sheetname "/")
		(sheetfile "thunderbolt-to-10gbe-adapter.kicad_sch")
		(attr exclude_from_pos_files exclude_from_bom)
		(fp_circle
			(center 0 0)
			(end 1.24 0)
			(stroke
				(width 0.05)
				(type solid)
			)
			(fill no)
			(layer "B.CrtYd")
		)
		(fp_circle
			(center 0 0)
			(end 0.999 0)
			(stroke
				(width 0.15)
				(type solid)
			)
			(fill no)
			(layer "B.Fab")
		)
		(fp_text user "License: Apache-2.0"
			(at -1.25 -7.003 0)
			(layer "B.Fab")
			(effects
				(font
					(size 0.7 0.7)
					(thickness 0.15)
				)
				(justify left bottom mirror)
			)
		)
		(fp_text user "${REFERENCE}"
			(at -1.25 -4.603 0)
			(layer "B.Fab")
			(effects
				(font
					(size 0.7 0.7)
					(thickness 0.15)
				)
				(justify left bottom mirror)
			)
		)
		(fp_text user "Author: Antmicro"
			(at -1.25 -5.803 0)
			(layer "B.Fab")
			(effects
				(font
					(size 0.7 0.7)
					(thickness 0.15)
				)
				(justify left bottom mirror)
			)
		)
		(pad "" smd circle
			(at 0 0 180)
			(size 1 1)
			(layers "B.Cu" "B.Mask")
			(solder_mask_margin 0.5)
			(clearance 0.5)
		)
	)
	(footprint "antmicro-footprints:TP_SMD_0.75mm"
		(layer "B.Cu")
		(at 183.75 80.25 90)
		(property "Reference" "TP16"
			(at -9.75 0.75 270)
			(layer "B.SilkS")
			(effects
				(font
					(size 0.7 0.7)
					(thickness 0.15)
				)
				(justify left bottom mirror)
			)
		)
		(property "Value" "TP_0.75mm_SMD"
			(at 0 -1.2 270)
			(layer "B.Fab")
			(effects
				(font
					(size 0.7 0.7)
					(thickness 0.15)
				)
				(justify left bottom mirror)
			)
		)
		(property "Description" "SMT test point"
			(at 0 0 270)
			(layer "B.Fab")
			(hide yes)
			(effects
				(font
					(size 1.27 1.27)
					(thickness 0.15)
				)
				(justify mirror)
			)
		)
		(property "MPN" ""
			(at 0 0 90)
			(unlocked yes)
			(layer "B.Fab")
			(hide yes)
			(effects
				(font
					(size 1 1)
					(thickness 0.15)
				)
				(justify mirror)
			)
		)
		(property "Manufacturer" ""
			(at 0 0 90)
			(unlocked yes)
			(layer "B.Fab")
			(hide yes)
			(effects
				(font
					(size 1 1)
					(thickness 0.15)
				)
				(justify mirror)
			)
		)
		(property "Author" "Antmicro"
			(at 0 0 90)
			(unlocked yes)
			(layer "B.Fab")
			(hide yes)
			(effects
				(font
					(size 1 1)
					(thickness 0.15)
				)
				(justify mirror)
			)
		)
		(property "License" "Apache-2.0"
			(at 0 0 90)
			(unlocked yes)
			(layer "B.Fab")
			(hide yes)
			(effects
				(font
					(size 1 1)
					(thickness 0.15)
				)
				(justify mirror)
			)
		)
		(sheetname "/X710 DCDC converters/")
		(sheetfile "DCDC_converters_X710.kicad_sch")
		(attr exclude_from_pos_files exclude_from_bom)
		(fp_circle
			(center 0 0)
			(end 0.475 0)
			(stroke
				(width 0.05)
				(type default)
			)
			(fill no)
			(layer "B.CrtYd")
		)
		(fp_text user "License: Apache-2.0"
			(at -0.4 -5.101 270)
			(layer "B.Fab")
			(effects
				(font
					(size 0.7 0.7)
					(thickness 0.15)
				)
				(justify left bottom mirror)
			)
		)
		(fp_text user "Author: Antmicro"
			(at -0.4 -3.901 270)
			(layer "B.Fab")
			(effects
				(font
					(size 0.7 0.7)
					(thickness 0.15)
				)
				(justify left bottom mirror)
			)
		)
		(fp_text user "${REFERENCE}"
			(at -0.4 -2.7 270)
			(layer "B.Fab")
			(effects
				(font
					(size 0.7 0.7)
					(thickness 0.15)
				)
				(justify left bottom mirror)
			)
		)
		(pad "1" smd circle
			(at 0 0 90)
			(size 0.75 0.75)
			(layers "B.Cu" "B.Mask")
			(net 9 "VCCD")
			(pinfunction "1")
			(pintype "passive")
		)
	)
	(footprint "antmicro-footprints:C_0402_1005Metric"
		(layer "B.Cu")
		(at 158.931866 89.755117)
		(descr "Capacitor SMD 0402")
		(tags "capacitor SMD 0402")
		(property "Reference" "C193"
			(at 20.068133 10.984883 180)
			(layer "B.SilkS")
			(effects
				(font
					(size 0.7 0.7)
					(thickness 0.15)
				)
				(justify mirror)
			)
		)
		(property "Value" "C_1u_25V_0402"
			(at -1.022927 -2.155213 180)
			(layer "B.Fab")
			(effects
				(font
					(size 0.7 0.7)
					(thickness 0.15)
				)
				(justify left bottom mirror)
			)
		)
		(property "Datasheet" "https://www.murata.com/products/productdetail?partno=GRM155R61E105KE11%23"
			(at 0 0 180)
			(layer "B.Fab")
			(hide yes)
			(effects
				(font
					(size 1.27 1.27)
					(thickness 0.15)
				)
				(justify mirror)
			)
		)
		(property "Description" "SMD Multilayer Ceramic Capacitor, 1 µF, 25 V, 0402 [1005 Metric], ± 10%, X5R, GRM Series"
			(at 0 0 180)
			(layer "B.Fab")
			(hide yes)
			(effects
				(font
					(size 1.27 1.27)
					(thickness 0.15)
				)
				(justify mirror)
			)
		)
		(property "MPN" "GRM155R61E105KE11J"
			(at 0 0 0)
			(unlocked yes)
			(layer "B.Fab")
			(hide yes)
			(effects
				(font
					(size 1 1)
					(thickness 0.15)
				)
				(justify mirror)
			)
		)
		(property "Manufacturer" "Murata"
			(at 0 0 0)
			(unlocked yes)
			(layer "B.Fab")
			(hide yes)
			(effects
				(font
					(size 1 1)
					(thickness 0.15)
				)
				(justify mirror)
			)
		)
		(property "License" "Apache-2.0"
			(at 0 0 0)
			(unlocked yes)
			(layer "B.Fab")
			(hide yes)
			(effects
				(font
					(size 1 1)
					(thickness 0.15)
				)
				(justify mirror)
			)
		)
		(property "Author" "Antmicro"
			(at 0 0 0)
			(unlocked yes)
			(layer "B.Fab")
			(hide yes)
			(effects
				(font
					(size 1 1)
					(thickness 0.15)
				)
				(justify mirror)
			)
		)
		(property "Val" "1u"
			(at 0 0 0)
			(unlocked yes)
			(layer "B.Fab")
			(hide yes)
			(effects
				(font
					(size 1 1)
					(thickness 0.15)
				)
				(justify mirror)
			)
		)
		(property "Voltage" "25V"
			(at 0 0 0)
			(unlocked yes)
			(layer "B.Fab")
			(hide yes)
			(effects
				(font
					(size 1 1)
					(thickness 0.15)
				)
				(justify mirror)
			)
		)
		(property "Dielectric" "X5R"
			(at 0 0 0)
			(unlocked yes)
			(layer "B.Fab")
			(hide yes)
			(effects
				(font
					(size 1 1)
					(thickness 0.15)
				)
				(justify mirror)
			)
		)
		(sheetname "/X710-AT2 power/")
		(sheetfile "x710-at2-power.kicad_sch")
		(attr smd)
		(fp_rect
			(start -0.925 0.47)
			(end 0.925 -0.47)
			(stroke
				(width 0.05)
				(type default)
			)
			(fill no)
			(layer "B.CrtYd")
		)
		(fp_line
			(start -0.494 -0.248)
			(end -0.494 0.25)
			(stroke
				(width 0.15)
				(type solid)
			)
			(layer "B.Fab")
		)
		(fp_line
			(start -0.494 0.25)
			(end 0.504 0.25)
			(stroke
				(width 0.15)
				(type solid)
			)
			(layer "B.Fab")
		)
		(fp_line
			(start 0.504 -0.248)
			(end -0.494 -0.248)
			(stroke
				(width 0.15)
				(type solid)
			)
			(layer "B.Fab")
		)
		(fp_line
			(start 0.504 0.25)
			(end 0.504 -0.248)
			(stroke
				(width 0.15)
				(type solid)
			)
			(layer "B.Fab")
		)
		(fp_text user "Author: Antmicro"
			(at -0.939 -3.399 180)
			(layer "B.Fab")
			(effects
				(font
					(size 0.7 0.7)
					(thickness 0.15)
				)
				(justify left bottom mirror)
			)
		)
		(fp_text user "License: Apache-2.0"
			(at -0.939 -5.799 180)
			(layer "B.Fab")
			(effects
				(font
					(size 0.7 0.7)
					(thickness 0.15)
				)
				(justify left bottom mirror)
			)
		)
		(fp_text user "${REFERENCE}"
			(at -0.939 -4.599 180)
			(layer "B.Fab")
			(effects
				(font
					(size 0.7 0.7)
					(thickness 0.15)
				)
				(justify left bottom mirror)
			)
		)
		(pad "1" smd roundrect
			(at -0.48 0)
			(size 0.59 0.64)
			(layers "B.Cu" "B.Mask" "B.Paste")
			(roundrect_rratio 0.25)
			(net 23 "GND")
			(pintype "passive")
		)
		(pad "2" smd roundrect
			(at 0.48 0)
			(size 0.59 0.64)
			(layers "B.Cu" "B.Mask" "B.Paste")
			(roundrect_rratio 0.25)
			(net 5 "P0_AVDDL")
			(pintype "passive")
		)
	)
)
